# T6G (Grand Teton) — schematic netlist excerpt (pin names and nets, part order shuffled) for the footprints in the layout excerpt that follows; sources: Cadence DE-HDL packaged netlist, KiCad conversion of 04192023_DAF0TMB3IC0_F0TG_MB_C_brd_V02_OCP.brd

R6739  Q_RES  1K 1% CHIP  pkg 0201LF  page 184 : A = P1V8_CPU1_RT_1D ; B = SMB_RT_CPU1_P1_R_SCL
R8564  Q_RES  0 5% CHIP  pkg 0402LF  page 28 : A = CLK_100M_CPU0_CLK02_R_DN ; B = CLK_100M_CPU0_CLK02_DN
C6678  Q_CAP_DIFFBUS  DIFF BUS_0.22UF 6.3V 20% X6S  pkg C0201  page 330 : \1\ = P5E_CPU1_P1_TX_BUF_C_DN<8> ; \2\ = P5E_CPU1_P1_TX_BUF_DN<8>
TP6  TP  NA  pkg TP  page 27 : TP = VSENSE_PVDDCR_CPU1_P0_DP

(kicad_pcb
	(version 20260206)
	(generator "pcbnew")
	(generator_version "10.0")
	(general
		(thickness 1.6)
		(legacy_teardrops no)
	)
	(paper "A4")
	(title_block
		(title "04192023_DAF0TMB3IC0_F0TG_MB_C_brd_V02_OCP.brd")
		(comment 1 "Grand Teton / footprints 5041-5044 of 8354")
	)
	(layers
		(0 "F.Cu" signal "TOP")
		(4 "In1.Cu" signal "GND")
		(6 "In2.Cu" signal "IN1")
		(8 "In3.Cu" signal "GND1")
		(10 "In4.Cu" signal "IN2")
		(12 "In5.Cu" signal "GND2")
		(14 "In6.Cu" signal "IN3")
		(16 "In7.Cu" signal "GND3")
		(18 "In8.Cu" signal "VCC")
		(20 "In9.Cu" signal "VCC1")
		(22 "In10.Cu" signal "GND4")
		(24 "In11.Cu" signal "IN4")
		(26 "In12.Cu" signal "GND5")
		(28 "In13.Cu" signal "IN5")
		(30 "In14.Cu" signal "GND6")
		(32 "In15.Cu" signal "IN6")
		(34 "In16.Cu" signal "GND7")
		(2 "B.Cu" signal "BOTTOM")
		(9 "F.Adhes" user "F.Adhesive")
		(11 "B.Adhes" user "B.Adhesive")
		(13 "F.Paste" user "Package Geometry/Pastemask Top")
		(15 "B.Paste" user "Package Geometry/Pastemask Bottom")
		(5 "F.SilkS" user "Ref Des/Silkscreen Top")
		(7 "B.SilkS" user "Ref Des/Silkscreen Bottom")
		(1 "F.Mask" user "Board Geometry/Soldermask Top")
		(3 "B.Mask" user "Board Geometry/Soldermask Bottom")
		(17 "Dwgs.User" user "User.Drawings")
		(19 "Cmts.User" user "User.Comments")
		(21 "Eco1.User" user "User.Eco1")
		(23 "Eco2.User" user "User.Eco2")
		(25 "Edge.Cuts" user "Board Geometry/Outline")
		(27 "Margin" user)
		(31 "F.CrtYd" user "Package Geometry/Place Bound Top")
		(29 "B.CrtYd" user "Package Geometry/Place Bound Bottom")
		(35 "F.Fab" user "Ref Des/Assembly Top")
		(33 "B.Fab" user "Ref Des/Assembly Bottom")
	)
	(footprint ""
		(layer "B.Cu")
		(at 380.075186 -214.523828 90)
		(property "Reference" "R8564"
			(at 0 0 90)
			(layer "B.SilkS")
			(hide yes)
			(effects
				(font
					(size 1.27 1.27)
				)
				(justify mirror)
			)
		)
		(property "Value" ""
			(at 0 0 90)
			(layer "B.Fab")
			(effects
				(font
					(size 1.27 1.27)
				)
				(justify mirror)
			)
		)
		(duplicate_pad_numbers_are_jumpers no)
		(fp_line
			(start 0.7874 -0.4064)
			(end -0.7874 -0.4064)
			(stroke
				(width 0.1524)
				(type default)
			)
			(layer "B.SilkS")
		)
		(fp_line
			(start -0.7874 -0.4064)
			(end -0.7874 0.010414)
			(stroke
				(width 0.1524)
				(type default)
			)
			(layer "B.SilkS")
		)
		(fp_line
			(start 0.7874 0.035814)
			(end 0.7874 -0.4064)
			(stroke
				(width 0.1524)
				(type default)
			)
			(layer "B.SilkS")
		)
		(fp_line
			(start -0.325628 0.4064)
			(end 0.436372 0.4064)
			(stroke
				(width 0.1524)
				(type default)
			)
			(layer "B.SilkS")
		)
		(fp_line
			(start 0.67945 -0.305054)
			(end 0.12065 -0.305054)
			(stroke
				(width 0.1)
				(type default)
			)
			(layer "B.Fab")
		)
		(fp_line
			(start 0.12065 -0.305054)
			(end 0.12065 -0.2794)
			(stroke
				(width 0.1)
				(type default)
			)
			(layer "B.Fab")
		)
		(fp_line
			(start -0.12065 -0.3048)
			(end -0.67945 -0.3048)
			(stroke
				(width 0.1)
				(type default)
			)
			(layer "B.Fab")
		)
		(fp_line
			(start -0.67945 -0.3048)
			(end -0.67945 0.3048)
			(stroke
				(width 0.1)
				(type default)
			)
			(layer "B.Fab")
		)
		(fp_line
			(start 0.12065 -0.2794)
			(end -0.12065 -0.2794)
			(stroke
				(width 0.1)
				(type default)
			)
			(layer "B.Fab")
		)
		(fp_line
			(start -0.12065 -0.2794)
			(end -0.12065 -0.3048)
			(stroke
				(width 0.1)
				(type default)
			)
			(layer "B.Fab")
		)
		(fp_line
			(start 0.12065 0.2794)
			(end 0.12065 0.3048)
			(stroke
				(width 0.1)
				(type default)
			)
			(layer "B.Fab")
		)
		(fp_line
			(start -0.120396 0.2794)
			(end 0.12065 0.2794)
			(stroke
				(width 0.1)
				(type default)
			)
			(layer "B.Fab")
		)
		(fp_line
			(start 0.67945 0.3048)
			(end 0.67945 -0.305054)
			(stroke
				(width 0.1)
				(type default)
			)
			(layer "B.Fab")
		)
		(fp_line
			(start 0.12065 0.3048)
			(end 0.67945 0.3048)
			(stroke
				(width 0.1)
				(type default)
			)
			(layer "B.Fab")
		)
		(fp_line
			(start -0.120396 0.3048)
			(end -0.120396 0.2794)
			(stroke
				(width 0.1)
				(type default)
			)
			(layer "B.Fab")
		)
		(fp_line
			(start -0.67945 0.3048)
			(end -0.120396 0.3048)
			(stroke
				(width 0.1)
				(type default)
			)
			(layer "B.Fab")
		)
		(pad "1" smd circle
			(at 0.40005 0 270)
			(size 0 0)
			(layers "B.Cu" "B.Mask" "B.Paste")
			(net "CLK_100M_CPU0_CLK02_R_DN")
		)
		(pad "2" smd circle
			(at -0.40005 0 270)
			(size 0 0)
			(layers "B.Cu" "B.Mask" "B.Paste")
			(net "CLK_100M_CPU0_CLK02_DN")
		)
	)
	(footprint ""
		(layer "B.Cu")
		(at 216.916 -337.439 90)
		(property "Reference" "R6739"
			(at 0 0 90)
			(layer "B.SilkS")
			(hide yes)
			(effects
				(font
					(size 1.27 1.27)
				)
				(justify mirror)
			)
		)
		(property "Value" ""
			(at 0 0 90)
			(layer "B.Fab")
			(effects
				(font
					(size 1.27 1.27)
				)
				(justify mirror)
			)
		)
		(duplicate_pad_numbers_are_jumpers no)
		(fp_line
			(start 0.32512 -0.175006)
			(end -0.32512 -0.175006)
			(stroke
				(width 0.1)
				(type default)
			)
			(layer "B.Fab")
		)
		(fp_line
			(start -0.32512 -0.175006)
			(end -0.32512 0.175006)
			(stroke
				(width 0.1)
				(type default)
			)
			(layer "B.Fab")
		)
		(fp_line
			(start 0.32512 0.175006)
			(end 0.32512 -0.175006)
			(stroke
				(width 0.1)
				(type default)
			)
			(layer "B.Fab")
		)
		(fp_line
			(start -0.32512 0.175006)
			(end 0.32512 0.175006)
			(stroke
				(width 0.1)
				(type default)
			)
			(layer "B.Fab")
		)
		(pad "1" smd rect
			(at 0.2667 0 270)
			(size 0.3048 0.381)
			(layers "B.Cu" "B.Mask" "B.Paste")
			(net "P1V8_CPU1_RT_1D")
		)
		(pad "2" smd rect
			(at -0.2667 0 90)
			(size 0.3048 0.381)
			(layers "B.Cu" "B.Mask" "B.Paste")
			(net "SMB_RT_CPU1_P1_R_SCL")
		)
	)
	(footprint ""
		(layer "B.Cu")
		(at 306.7304 -354.076 180)
		(property "Reference" "TP6"
			(at 0.69088 -0.114554 0)
			(unlocked yes)
			(layer "B.SilkS")
			(effects
				(font
					(size 0.7874 0.5842)
					(thickness 0.1524)
				)
				(justify left mirror)
			)
		)
		(property "Value" ""
			(at 0 0 0)
			(layer "B.Fab")
			(effects
				(font
					(size 1.27 1.27)
				)
				(justify mirror)
			)
		)
		(duplicate_pad_numbers_are_jumpers no)
		(pad "1" smd circle
			(at 0 0)
			(size 0.762 0.762)
			(layers "B.Cu" "B.Mask" "B.Paste")
			(net "VSENSE_PVDDCR_CPU1_P0_DP")
		)
	)
	(footprint ""
		(layer "B.Cu")
		(at 73.806304 -408.517344 90)
		(property "Reference" "C6678"
			(at 0 0 90)
			(layer "B.SilkS")
			(hide yes)
			(effects
				(font
					(size 1.27 1.27)
				)
				(justify mirror)
			)
		)
		(property "Value" ""
			(at 0 0 90)
			(layer "B.Fab")
			(effects
				(font
					(size 1.27 1.27)
				)
				(justify mirror)
			)
		)
		(duplicate_pad_numbers_are_jumpers no)
		(fp_line
			(start 0.299974 -0.150114)
			(end -0.299974 -0.150114)
			(stroke
				(width 0.1)
				(type default)
			)
			(layer "B.Fab")
		)
		(fp_line
			(start -0.299974 -0.150114)
			(end -0.299974 0.150114)
			(stroke
				(width 0.1)
				(type default)
			)
			(layer "B.Fab")
		)
		(fp_line
			(start 0.299974 0.150114)
			(end 0.299974 -0.150114)
			(stroke
				(width 0.1)
				(type default)
			)
			(layer "B.Fab")
		)
		(fp_line
			(start -0.299974 0.150114)
			(end 0.299974 0.150114)
			(stroke
				(width 0.1)
				(type default)
			)
			(layer "B.Fab")
		)
		(pad "1" smd rect
			(at 0.2667 0 270)
			(size 0.3048 0.381)
			(layers "B.Cu" "B.Mask" "B.Paste")
			(net "P5E_CPU1_P1_TX_BUF_C_DN<8>")
		)
		(pad "2" smd rect
			(at -0.2667 0 270)
			(size 0.3048 0.381)
			(layers "B.Cu" "B.Mask" "B.Paste")
			(net "P5E_CPU1_P1_TX_BUF_DN<8>")
		)
	)
)
